(kicad_pcb
	(version 20260206)
	(generator "pcbnew")
	(generator_version "10.0")
	(general
		(thickness 1.6)
		(legacy_teardrops no)
	)
	(paper "A4")
	(title_block
		(title "03242023_DA0F0TMBIJ0_F0T_Motherboard_J_brd_V01_OCP.brd")
		(comment 1 "Grand Teton / footprints 3239-3242 of 6105")
	)
	(layers
		(0 "F.Cu" signal "TOP")
		(4 "In1.Cu" signal "GND")
		(6 "In2.Cu" signal "IN1")
		(8 "In3.Cu" signal "GND1")
		(10 "In4.Cu" signal "IN2")
		(12 "In5.Cu" signal "GND2")
		(14 "In6.Cu" signal "IN3")
		(16 "In7.Cu" signal "GND3")
		(18 "In8.Cu" signal "VCC")
		(20 "In9.Cu" signal "VCC1")
		(22 "In10.Cu" signal "GND4")
		(24 "In11.Cu" signal "IN4")
		(26 "In12.Cu" signal "GND5")
		(28 "In13.Cu" signal "IN5")
		(30 "In14.Cu" signal "GND6")
		(32 "In15.Cu" signal "IN6")
		(34 "In16.Cu" signal "GND7")
		(2 "B.Cu" signal "BOTTOM")
		(9 "F.Adhes" user "F.Adhesive")
		(11 "B.Adhes" user "B.Adhesive")
		(13 "F.Paste" user "Package Geometry/Pastemask Top")
		(15 "B.Paste" user "Package Geometry/Pastemask Bottom")
		(5 "F.SilkS" user "Ref Des/Silkscreen Top")
		(7 "B.SilkS" user "Ref Des/Silkscreen Bottom")
		(1 "F.Mask" user "Board Geometry/Soldermask Top")
		(3 "B.Mask" user "Board Geometry/Soldermask Bottom")
		(17 "Dwgs.User" user "User.Drawings")
		(19 "Cmts.User" user "User.Comments")
		(21 "Eco1.User" user "User.Eco1")
		(23 "Eco2.User" user "User.Eco2")
		(25 "Edge.Cuts" user "Board Geometry/Outline")
		(27 "Margin" user)
		(31 "F.CrtYd" user "Package Geometry/Place Bound Top")
		(29 "B.CrtYd" user "Package Geometry/Place Bound Bottom")
		(35 "F.Fab" user "Ref Des/Assembly Top")
		(33 "B.Fab" user "Ref Des/Assembly Bottom")
	)
	(footprint ""
		(layer "F.Cu")
		(at 39.960042 -392.430254 180)
		(property "Reference" "U328"
			(at 6.072124 -4.195318 0)
			(unlocked yes)
			(layer "F.SilkS")
			(effects
				(font
					(size 0.7874 0.5842)
					(thickness 0.1524)
				)
				(justify left)
			)
		)
		(property "Value" ""
			(at 0 0 180)
			(layer "F.Fab")
			(effects
				(font
					(size 1.27 1.27)
				)
			)
		)
		(duplicate_pad_numbers_are_jumpers no)
		(fp_line
			(start 2.050034 2.050034)
			(end 1.524 2.050034)
			(stroke
				(width 0.1524)
				(type default)
			)
			(layer "F.SilkS")
		)
		(fp_line
			(start 2.050034 1.524)
			(end 2.050034 2.050034)
			(stroke
				(width 0.1524)
				(type default)
			)
			(layer "F.SilkS")
		)
		(fp_line
			(start 2.050034 -2.050034)
			(end 2.050034 -1.524)
			(stroke
				(width 0.1524)
				(type default)
			)
			(layer "F.SilkS")
		)
		(fp_line
			(start 1.524 -2.050034)
			(end 2.050034 -2.050034)
			(stroke
				(width 0.1524)
				(type default)
			)
			(layer "F.SilkS")
		)
		(fp_line
			(start -1.524 2.050034)
			(end -2.050034 2.050034)
			(stroke
				(width 0.1524)
				(type default)
			)
			(layer "F.SilkS")
		)
		(fp_line
			(start -2.050034 2.050034)
			(end -2.050034 1.524)
			(stroke
				(width 0.1524)
				(type default)
			)
			(layer "F.SilkS")
		)
		(fp_line
			(start -2.050034 -1.524)
			(end -2.050034 -2.050034)
			(stroke
				(width 0.1524)
				(type default)
			)
			(layer "F.SilkS")
		)
		(fp_line
			(start -2.050034 -2.050034)
			(end -1.524 -2.050034)
			(stroke
				(width 0.1524)
				(type default)
			)
			(layer "F.SilkS")
		)
		(fp_poly
			(pts
				(xy -2.634234 -1.542034) (xy -2.050034 -1.542034) (xy -2.050034 -2.126234) (xy -2.634234 -2.126234)
			)
			(stroke
				(width 0)
				(type default)
			)
			(fill yes)
			(layer "F.SilkS")
		)
		(fp_line
			(start 2.050034 2.050034)
			(end -2.050034 2.050034)
			(stroke
				(width 0.1)
				(type default)
			)
			(layer "F.Fab")
		)
		(fp_line
			(start 2.050034 -2.050034)
			(end 2.050034 2.050034)
			(stroke
				(width 0.1)
				(type default)
			)
			(layer "F.Fab")
		)
		(fp_line
			(start -2.050034 2.050034)
			(end -2.050034 -2.050034)
			(stroke
				(width 0.1)
				(type default)
			)
			(layer "F.Fab")
		)
		(fp_line
			(start -2.050034 -2.050034)
			(end 2.050034 -2.050034)
			(stroke
				(width 0.1)
				(type default)
			)
			(layer "F.Fab")
		)
		(fp_poly
			(pts
				(xy -2.634234 -1.542034) (xy -2.050034 -1.542034) (xy -2.050034 -2.126234) (xy -2.634234 -2.126234)
			)
			(stroke
				(width 0)
				(type default)
			)
			(fill yes)
			(layer "F.Fab")
		)
		(pad "1" smd circle
			(at -1.89992 -1.249934 90)
			(size 0 0)
			(layers "F.Cu" "F.Mask" "F.Paste")
			(net "FM_P2E_BUF2_EQB0")
		)
		(pad "2" smd circle
			(at -1.89992 -0.750062 90)
			(size 0 0)
			(layers "F.Cu" "F.Mask" "F.Paste")
			(net "FM_P2E_BUF2_EQB1")
		)
		(pad "3" smd circle
			(at -1.89992 -0.249936 90)
			(size 0 0)
			(layers "F.Cu" "F.Mask" "F.Paste")
			(net "PD_P2E_BUF2_ENSMB")
		)
		(pad "4" smd circle
			(at -1.89992 0.249936 90)
			(size 0 0)
			(layers "F.Cu" "F.Mask" "F.Paste")
			(net "FM_P2E_BUF2_VODA_DB")
		)
		(pad "5" smd circle
			(at -1.89992 0.750062 90)
			(size 0 0)
			(layers "F.Cu" "F.Mask" "F.Paste")
			(net "FM_P2E_BUF2_VODB_DB")
		)
		(pad "6" smd circle
			(at -1.89992 1.249934 90)
			(size 0 0)
			(layers "F.Cu" "F.Mask" "F.Paste")
			(net "FM_P2E_EN2_N")
		)
		(pad "7" smd circle
			(at -1.249934 1.89992 180)
			(size 0 0)
			(layers "F.Cu" "F.Mask" "F.Paste")
			(net "P2E_MB_BMC_TX_BUF2_DP<0>")
		)
		(pad "8" smd circle
			(at -0.750062 1.89992 180)
			(size 0 0)
			(layers "F.Cu" "F.Mask" "F.Paste")
			(net "P2E_MB_BMC_TX_BUF2_DN<0>")
		)
		(pad "9" smd circle
			(at -0.249936 1.89992 180)
			(size 0 0)
			(layers "F.Cu" "F.Mask" "F.Paste")
			(net "FM_P2E_BUF2_EQA1")
		)
		(pad "10" smd circle
			(at 0.249936 1.89992 180)
			(size 0 0)
			(layers "F.Cu" "F.Mask" "F.Paste")
			(net "FM_P2E_BUF2_EQA0")
		)
		(pad "11" smd circle
			(at 0.750062 1.89992 180)
			(size 0 0)
			(layers "F.Cu" "F.Mask" "F.Paste")
			(net "P2E_MB_BMC_RX_R2_DP<0>")
		)
		(pad "12" smd circle
			(at 1.249934 1.89992 180)
			(size 0 0)
			(layers "F.Cu" "F.Mask" "F.Paste")
			(net "P2E_MB_BMC_RX_R2_DN<0>")
		)
		(pad "13" smd circle
			(at 1.89992 1.249934 90)
			(size 0 0)
			(layers "F.Cu" "F.Mask" "F.Paste")
			(net "NC_RES")
		)
		(pad "14" smd circle
			(at 1.89992 0.750062 90)
			(size 0 0)
			(layers "F.Cu" "F.Mask" "F.Paste")
			(net "FM_P2E_BUF2_SD_TH")
		)
		(pad "15" smd circle
			(at 1.89992 0.249936 90)
			(size 0 0)
			(layers "F.Cu" "F.Mask" "F.Paste")
			(net "P3V3_AUX")
		)
		(pad "16" smd circle
			(at 1.89992 -0.249936 90)
			(size 0 0)
			(layers "F.Cu" "F.Mask" "F.Paste")
			(net "GND")
		)
		(pad "17" smd circle
			(at 1.89992 -0.750062 90)
			(size 0 0)
			(layers "F.Cu" "F.Mask" "F.Paste")
			(net "FM_P2E_BUF2_VOD_SEL")
		)
		(pad "18" smd circle
			(at 1.89992 -1.249934 90)
			(size 0 0)
			(layers "F.Cu" "F.Mask" "F.Paste")
			(net "FM_P2E_BUF2_RXDET")
		)
		(pad "19" smd circle
			(at 1.249934 -1.89992 180)
			(size 0 0)
			(layers "F.Cu" "F.Mask" "F.Paste")
			(net "P2E_MB_BMC_RX_BUF2_C_DN<0>")
		)
		(pad "20" smd circle
			(at 0.750062 -1.89992 180)
			(size 0 0)
			(layers "F.Cu" "F.Mask" "F.Paste")
			(net "P2E_MB_BMC_RX_BUF2_C_DP<0>")
		)
		(pad "21" smd circle
			(at 0.249936 -1.89992 180)
			(size 0 0)
			(layers "F.Cu" "F.Mask" "F.Paste")
			(net "P2E_BUF2_VDD")
		)
		(pad "22" smd circle
			(at -0.249936 -1.89992 180)
			(size 0 0)
			(layers "F.Cu" "F.Mask" "F.Paste")
			(net "P2E_BUF2_VDD")
		)
		(pad "23" smd circle
			(at -0.750062 -1.89992 180)
			(size 0 0)
			(layers "F.Cu" "F.Mask" "F.Paste")
			(net "P2E_MB_BMC_TX_C_R2_DN<0>")
		)
		(pad "24" smd circle
			(at -1.249934 -1.89992 180)
			(size 0 0)
			(layers "F.Cu" "F.Mask" "F.Paste")
			(net "P2E_MB_BMC_TX_C_R2_DP<0>")
		)
		(pad "25" smd circle
			(at 0 0 180)
			(size 0 0)
			(layers "F.Cu" "F.Mask" "F.Paste")
			(net "GND")
		)
	)
	(footprint ""
		(layer "F.Cu")
		(at 373.654828 -358.460548)
		(property "Reference" "PU79"
			(at 2.394966 2.31775 0)
			(unlocked yes)
			(layer "F.SilkS")
			(effects
				(font
					(size 0.7874 0.5842)
					(thickness 0.1524)
				)
				(justify left)
			)
		)
		(property "Value" ""
			(at 0 0 0)
			(layer "F.Fab")
			(effects
				(font
					(size 1.27 1.27)
				)
			)
		)
		(duplicate_pad_numbers_are_jumpers no)
		(fp_line
			(start -1.549908 -2.050034)
			(end -1.549908 -1.9812)
			(stroke
				(width 0.1524)
				(type default)
			)
			(layer "F.SilkS")
		)
		(fp_line
			(start -1.549908 1.9812)
			(end -1.549908 2.050034)
			(stroke
				(width 0.1524)
				(type default)
			)
			(layer "F.SilkS")
		)
		(fp_line
			(start -1.549908 2.050034)
			(end -0.5842 2.050034)
			(stroke
				(width 0.1524)
				(type default)
			)
			(layer "F.SilkS")
		)
		(fp_line
			(start -0.5842 -2.050034)
			(end -1.549908 -2.050034)
			(stroke
				(width 0.1524)
				(type default)
			)
			(layer "F.SilkS")
		)
		(fp_line
			(start 0 2.050034)
			(end 1.549908 2.050034)
			(stroke
				(width 0.1524)
				(type default)
			)
			(layer "F.SilkS")
		)
		(fp_line
			(start 1.549908 -2.050034)
			(end 0.5842 -2.050034)
			(stroke
				(width 0.1524)
				(type default)
			)
			(layer "F.SilkS")
		)
		(fp_line
			(start 1.549908 -1.9812)
			(end 1.549908 -2.050034)
			(stroke
				(width 0.1524)
				(type default)
			)
			(layer "F.SilkS")
		)
		(fp_line
			(start 1.549908 2.050034)
			(end 1.549908 1.9304)
			(stroke
				(width 0.1524)
				(type default)
			)
			(layer "F.SilkS")
		)
		(fp_poly
			(pts
				(xy -3.216402 -2.222246) (xy -3.216402 -1.206246) (xy -2.200402 -1.714246)
			)
			(stroke
				(width 0)
				(type default)
			)
			(fill yes)
			(layer "F.SilkS")
		)
		(fp_line
			(start -1.549908 -2.050034)
			(end -1.549908 2.050034)
			(stroke
				(width 0.1)
				(type default)
			)
			(layer "F.Fab")
		)
		(fp_line
			(start -1.549908 2.050034)
			(end 1.549908 2.050034)
			(stroke
				(width 0.1)
				(type default)
			)
			(layer "F.Fab")
		)
		(fp_line
			(start 1.549908 -2.050034)
			(end -1.549908 -2.050034)
			(stroke
				(width 0.1)
				(type default)
			)
			(layer "F.Fab")
		)
		(fp_line
			(start 1.549908 2.050034)
			(end 1.549908 -2.050034)
			(stroke
				(width 0.1)
				(type default)
			)
			(layer "F.Fab")
		)
		(fp_poly
			(pts
				(xy -2.9464 -2.208022) (xy -2.9464 -1.192022) (xy -1.9304 -1.700022)
			)
			(stroke
				(width 0)
				(type default)
			)
			(fill yes)
			(layer "F.Fab")
		)
		(pad "1" smd circle
			(at -1.35001 -1.700022)
			(size 0 0)
			(layers "F.Cu" "F.Mask" "F.Paste")
			(net "SW_PVPP_HBM_CPU0_BST")
		)
		(pad "2" smd rect
			(at -1.400048 -1.199896 90)
			(size 0.1778 0.8128)
			(layers "F.Cu" "F.Mask" "F.Paste")
			(net "GND")
		)
		(pad "3" smd rect
			(at -1.400048 -0.8001 90)
			(size 0.1778 0.8128)
			(layers "F.Cu" "F.Mask" "F.Paste")
			(net "PVPP_HBM_CPU0_CS")
		)
		(pad "4" smd rect
			(at -1.400048 -0.40005 90)
			(size 0.1778 0.8128)
			(layers "F.Cu" "F.Mask" "F.Paste")
			(net "PVPP_HBM_CPU0_MODE")
		)
		(pad "5" smd rect
			(at -1.400048 0 90)
			(size 0.1778 0.8128)
			(layers "F.Cu" "F.Mask" "F.Paste")
			(net "PVPP_HBM_CPU0_REF")
		)
		(pad "6" smd rect
			(at -1.400048 0.40005 90)
			(size 0.1778 0.8128)
			(layers "F.Cu" "F.Mask" "F.Paste")
			(net "SH_PVPP_HBM_CPU0_N")
		)
		(pad "7" smd rect
			(at -1.400048 0.8001 90)
			(size 0.1778 0.8128)
			(layers "F.Cu" "F.Mask" "F.Paste")
			(net "PVPP_HBM_CPU0_FB")
		)
		(pad "8" smd rect
			(at -1.400048 1.199896 90)
			(size 0.1778 0.8128)
			(layers "F.Cu" "F.Mask" "F.Paste")
			(net "FM_PVPP_HBM_CPU0_EN")
		)
		(pad "9" smd rect
			(at -1.400048 1.700022 90)
			(size 0.3048 0.8128)
			(layers "F.Cu" "F.Mask" "F.Paste")
			(net "PWRGD_PVPP_HBM_CPU0_R")
		)
		(pad "10" smd rect
			(at -0.299974 1.299972)
			(size 0.3048 2.0066)
			(layers "F.Cu" "F.Mask" "F.Paste")
			(net "SW_P12V_PVCCIN_CPU0_FLT")
		)
		(pad "11_18" smd circle
			(at 1.175004 0.275082)
			(size 0 0)
			(layers "F.Cu" "F.Mask" "F.Paste")
			(net "GND")
		)
		(pad "19" smd rect
			(at 1.400048 -1.700022 270)
			(size 0.3048 0.8128)
			(layers "F.Cu" "F.Mask" "F.Paste")
			(net "PVPP_HBM_CPU0_VCC")
		)
		(pad "20" smd rect
			(at 0.299974 -1.299972)
			(size 0.3048 2.0066)
			(layers "F.Cu" "F.Mask" "F.Paste")
			(net "SW_PVPP_HBM_CPU0_SW")
		)
		(pad "21" smd rect
			(at -0.299974 -1.299972)
			(size 0.3048 2.0066)
			(layers "F.Cu" "F.Mask" "F.Paste")
			(net "SW_P12V_PVCCIN_CPU0_FLT")
		)
	)
	(footprint ""
		(layer "F.Cu")
		(at 190.4238 -42.554398)
		(property "Reference" "R4071"
			(at 0 0 0)
			(layer "F.SilkS")
			(hide yes)
			(effects
				(font
					(size 1.27 1.27)
				)
			)
		)
		(property "Value" ""
			(at 0 0 0)
			(layer "F.Fab")
			(effects
				(font
					(size 1.27 1.27)
				)
			)
		)
		(duplicate_pad_numbers_are_jumpers no)
		(fp_line
			(start -0.7874 -0.4064)
			(end 0.7874 -0.4064)
			(stroke
				(width 0.1524)
				(type default)
			)
			(layer "F.SilkS")
		)
		(fp_line
			(start -0.7874 0.4064)
			(end -0.7874 -0.4064)
			(stroke
				(width 0.1524)
				(type default)
			)
			(layer "F.SilkS")
		)
		(fp_line
			(start 0.7874 -0.4064)
			(end 0.7874 0.4064)
			(stroke
				(width 0.1524)
				(type default)
			)
			(layer "F.SilkS")
		)
		(fp_line
			(start 0.7874 0.4064)
			(end -0.7874 0.4064)
			(stroke
				(width 0.1524)
				(type default)
			)
			(layer "F.SilkS")
		)
		(fp_line
			(start -0.67945 -0.305054)
			(end -0.12065 -0.305054)
			(stroke
				(width 0.1)
				(type default)
			)
			(layer "F.Fab")
		)
		(fp_line
			(start -0.67945 0.3048)
			(end -0.67945 -0.305054)
			(stroke
				(width 0.1)
				(type default)
			)
			(layer "F.Fab")
		)
		(fp_line
			(start -0.12065 -0.305054)
			(end -0.12065 -0.2794)
			(stroke
				(width 0.1)
				(type default)
			)
			(layer "F.Fab")
		)
		(fp_line
			(start -0.12065 -0.2794)
			(end 0.12065 -0.2794)
			(stroke
				(width 0.1)
				(type default)
			)
			(layer "F.Fab")
		)
		(fp_line
			(start -0.12065 0.2794)
			(end -0.12065 0.3048)
			(stroke
				(width 0.1)
				(type default)
			)
			(layer "F.Fab")
		)
		(fp_line
			(start -0.12065 0.3048)
			(end -0.67945 0.3048)
			(stroke
				(width 0.1)
				(type default)
			)
			(layer "F.Fab")
		)
		(fp_line
			(start 0.120396 0.2794)
			(end -0.12065 0.2794)
			(stroke
				(width 0.1)
				(type default)
			)
			(layer "F.Fab")
		)
		(fp_line
			(start 0.120396 0.3048)
			(end 0.120396 0.2794)
			(stroke
				(width 0.1)
				(type default)
			)
			(layer "F.Fab")
		)
		(fp_line
			(start 0.12065 -0.3048)
			(end 0.67945 -0.3048)
			(stroke
				(width 0.1)
				(type default)
			)
			(layer "F.Fab")
		)
		(fp_line
			(start 0.12065 -0.2794)
			(end 0.12065 -0.3048)
			(stroke
				(width 0.1)
				(type default)
			)
			(layer "F.Fab")
		)
		(fp_line
			(start 0.67945 -0.3048)
			(end 0.67945 0.3048)
			(stroke
				(width 0.1)
				(type default)
			)
			(layer "F.Fab")
		)
		(fp_line
			(start 0.67945 0.3048)
			(end 0.120396 0.3048)
			(stroke
				(width 0.1)
				(type default)
			)
			(layer "F.Fab")
		)
		(pad "1" smd circle
			(at -0.40005 0)
			(size 0 0)
			(layers "F.Cu" "F.Mask" "F.Paste")
			(net "P12V_AUX")
		)
		(pad "2" smd circle
			(at 0.40005 0)
			(size 0 0)
			(layers "F.Cu" "F.Mask" "F.Paste")
			(net "P12V_SCM_EN_G")
		)
	)
	(footprint ""
		(layer "F.Cu")
		(at 116.561616 -255.0541 90)
		(property "Reference" "C305"
			(at 0 0 90)
			(layer "F.SilkS")
			(hide yes)
			(effects
				(font
					(size 1.27 1.27)
				)
			)
		)
		(property "Value" ""
			(at 0 0 90)
			(layer "F.Fab")
			(effects
				(font
					(size 1.27 1.27)
				)
			)
		)
		(duplicate_pad_numbers_are_jumpers no)
		(fp_line
			(start 0.7874 -0.4064)
			(end 0.7874 0.4064)
			(stroke
				(width 0.1524)
				(type default)
			)
			(layer "F.SilkS")
		)
		(fp_line
			(start -0.7874 -0.4064)
			(end 0.7874 -0.4064)
			(stroke
				(width 0.1524)
				(type default)
			)
			(layer "F.SilkS")
		)
		(fp_line
			(start 0.7874 0.4064)
			(end -0.7874 0.4064)
			(stroke
				(width 0.1524)
				(type default)
			)
			(layer "F.SilkS")
		)
		(fp_line
			(start -0.7874 0.4064)
			(end -0.7874 -0.4064)
			(stroke
				(width 0.1524)
				(type default)
			)
			(layer "F.SilkS")
		)
		(fp_line
			(start -0.12065 -0.305054)
			(end -0.12065 -0.2794)
			(stroke
				(width 0.1)
				(type default)
			)
			(layer "F.Fab")
		)
		(fp_line
			(start -0.67945 -0.305054)
			(end -0.12065 -0.305054)
			(stroke
				(width 0.1)
				(type default)
			)
			(layer "F.Fab")
		)
		(fp_line
			(start 0.67945 -0.3048)
			(end 0.67945 0.3048)
			(stroke
				(width 0.1)
				(type default)
			)
			(layer "F.Fab")
		)
		(fp_line
			(start 0.12065 -0.3048)
			(end 0.67945 -0.3048)
			(stroke
				(width 0.1)
				(type default)
			)
			(layer "F.Fab")
		)
		(fp_line
			(start 0.12065 -0.2794)
			(end 0.12065 -0.3048)
			(stroke
				(width 0.1)
				(type default)
			)
			(layer "F.Fab")
		)
		(fp_line
			(start -0.12065 -0.2794)
			(end 0.12065 -0.2794)
			(stroke
				(width 0.1)
				(type default)
			)
			(layer "F.Fab")
		)
		(fp_line
			(start 0.120396 0.2794)
			(end -0.12065 0.2794)
			(stroke
				(width 0.1)
				(type default)
			)
			(layer "F.Fab")
		)
		(fp_line
			(start -0.12065 0.2794)
			(end -0.12065 0.3048)
			(stroke
				(width 0.1)
				(type default)
			)
			(layer "F.Fab")
		)
		(fp_line
			(start 0.67945 0.3048)
			(end 0.120396 0.3048)
			(stroke
				(width 0.1)
				(type default)
			)
			(layer "F.Fab")
		)
		(fp_line
			(start 0.120396 0.3048)
			(end 0.120396 0.2794)
			(stroke
				(width 0.1)
				(type default)
			)
			(layer "F.Fab")
		)
		(fp_line
			(start -0.12065 0.3048)
			(end -0.67945 0.3048)
			(stroke
				(width 0.1)
				(type default)
			)
			(layer "F.Fab")
		)
		(fp_line
			(start -0.67945 0.3048)
			(end -0.67945 -0.305054)
			(stroke
				(width 0.1)
				(type default)
			)
			(layer "F.Fab")
		)
		(pad "1" smd circle
			(at -0.40005 0 90)
			(size 0 0)
			(layers "F.Cu" "F.Mask" "F.Paste")
			(net "PVCCIN_CPU1")
		)
		(pad "2" smd circle
			(at 0.40005 0 90)
			(size 0 0)
			(layers "F.Cu" "F.Mask" "F.Paste")
			(net "GND")
		)
	)
)
